(kicad_pcb
	(version 20241229)
	(generator "pcbnew")
	(generator_version "9.0")
	(general
		(thickness 1.552)
		(legacy_teardrops no)
	)
	(paper "A4")
	(title_block
		(date "2023-07-25")
		(rev "1.1.4")
		(comment 9 "footprints 299-303 of 379")
	)
	(layers
		(0 "F.Cu" signal)
		(4 "In1.Cu" signal)
		(6 "In2.Cu" signal)
		(8 "In3.Cu" signal)
		(10 "In4.Cu" signal)
		(12 "In5.Cu" signal)
		(14 "In6.Cu" signal)
		(2 "B.Cu" signal)
		(9 "F.Adhes" user "F.Adhesive")
		(11 "B.Adhes" user "B.Adhesive")
		(13 "F.Paste" user)
		(15 "B.Paste" user)
		(5 "F.SilkS" user "F.Silkscreen")
		(7 "B.SilkS" user "B.Silkscreen")
		(1 "F.Mask" user)
		(3 "B.Mask" user)
		(17 "Dwgs.User" user "User.Drawings")
		(19 "Cmts.User" user "User.Comments")
		(21 "Eco1.User" user "User.Eco1")
		(23 "Eco2.User" user "User.Eco2")
		(25 "Edge.Cuts" user)
		(27 "Margin" user)
		(31 "F.CrtYd" user "F.Courtyard")
		(29 "B.CrtYd" user "B.Courtyard")
		(35 "F.Fab" user)
		(33 "B.Fab" user)
	)
	(footprint "antmicro-footprints:R_0402_1005Metric"
		(layer "B.Cu")
		(at 105.19 96.8 -90)
		(descr "Resistor SMD 0402")
		(tags "resistor SMD 0402")
		(property "Reference" "R75"
			(at 0.94 -0.34 90)
			(layer "B.SilkS")
			(effects
				(font
					(size 0.65 0.65)
					(thickness 0.15)
				)
				(justify left bottom mirror)
			)
		)
		(property "Value" "R_0R_0402"
			(at 0 -1.4 90)
			(layer "B.Fab")
			(hide yes)
			(effects
				(font
					(size 0.7 0.7)
					(thickness 0.15)
				)
				(justify left bottom mirror)
			)
		)
		(property "Datasheet" "https://industrial.panasonic.com/cdbs/www-data/pdf/RDA0000/AOA0000C301.pdf"
			(at 0 0 270)
			(layer "F.Fab")
			(hide yes)
			(effects
				(font
					(size 1.27 1.27)
					(thickness 0.15)
				)
			)
		)
		(property "Description" "SMD Chip Resistor, Jumper, 0 ohm, 100 mW, 0402 [1005 Metric], Thick Film, General Purpose"
			(at 0 0 270)
			(layer "F.Fab")
			(hide yes)
			(effects
				(font
					(size 1.27 1.27)
					(thickness 0.15)
				)
			)
		)
		(property "Author" "Antmicro"
			(at 8.39 201.99 0)
			(layer "B.Fab")
			(hide yes)
			(effects
				(font
					(size 1 1)
					(thickness 0.15)
				)
				(justify mirror)
			)
		)
		(property "Current" "1A"
			(at 8.39 201.99 0)
			(layer "B.Fab")
			(hide yes)
			(effects
				(font
					(size 1 1)
					(thickness 0.15)
				)
				(justify mirror)
			)
		)
		(property "License" "Apache-2.0"
			(at 8.39 201.99 0)
			(layer "B.Fab")
			(hide yes)
			(effects
				(font
					(size 1 1)
					(thickness 0.15)
				)
				(justify mirror)
			)
		)
		(property "MPN" "ERJ2GE0R00X"
			(at 8.39 201.99 0)
			(layer "B.Fab")
			(hide yes)
			(effects
				(font
					(size 1 1)
					(thickness 0.15)
				)
				(justify mirror)
			)
		)
		(property "Manufacturer" "Panasonic"
			(at 8.39 201.99 0)
			(layer "B.Fab")
			(hide yes)
			(effects
				(font
					(size 1 1)
					(thickness 0.15)
				)
				(justify mirror)
			)
		)
		(property "Tolerance" "~"
			(at 8.39 201.99 0)
			(layer "B.Fab")
			(hide yes)
			(effects
				(font
					(size 1 1)
					(thickness 0.15)
				)
				(justify mirror)
			)
		)
		(property "Val" "0R"
			(at 8.39 201.99 0)
			(layer "B.Fab")
			(hide yes)
			(effects
				(font
					(size 1 1)
					(thickness 0.15)
				)
				(justify mirror)
			)
		)
		(sheetname "/FPGA/")
		(sheetfile "fpga.kicad_sch")
		(attr smd)
		(fp_rect
			(start -0.925 0.47)
			(end 0.925 -0.47)
			(stroke
				(width 0.05)
				(type default)
			)
			(fill no)
			(layer "B.CrtYd")
		)
		(fp_rect
			(start -0.5 0.25)
			(end 0.5 -0.25)
			(stroke
				(width 0.15)
				(type solid)
			)
			(fill no)
			(layer "B.Fab")
		)
		(fp_text user "License: Apache-2.0"
			(at -0.95 -5.169 90)
			(layer "B.Fab")
			(effects
				(font
					(size 0.7 0.7)
					(thickness 0.15)
				)
				(justify left bottom mirror)
			)
		)
		(fp_text user "Author: Antmicro"
			(at -0.95 -4.169 90)
			(layer "B.Fab")
			(effects
				(font
					(size 0.7 0.7)
					(thickness 0.15)
				)
				(justify left bottom mirror)
			)
		)
		(fp_text user "${REFERENCE}"
			(at -0.95 -3.168 90)
			(layer "B.Fab")
			(effects
				(font
					(size 0.7 0.7)
					(thickness 0.15)
				)
				(justify left bottom mirror)
			)
		)
		(pad "1" smd roundrect
			(at -0.48 0 270)
			(size 0.59 0.64)
			(layers "B.Cu" "B.Mask" "B.Paste")
			(roundrect_rratio 0.25)
			(net 303 "Net-(U18-SCLK)")
			(pintype "passive")
		)
		(pad "2" smd roundrect
			(at 0.48 0 270)
			(size 0.59 0.64)
			(layers "B.Cu" "B.Mask" "B.Paste")
			(roundrect_rratio 0.25)
			(net 39 "/FPGA/SPI_CLK")
			(pintype "passive")
		)
	)
	(footprint "antmicro-footprints:C_0402_1005Metric"
		(layer "B.Cu")
		(at 128.37 59.62 -45)
		(descr "Capacitor SMD 0402")
		(tags "capacitor SMD 0402")
		(property "Reference" "C43"
			(at 0.374767 1.378858 135)
			(layer "B.SilkS")
			(effects
				(font
					(size 0.65 0.65)
					(thickness 0.15)
				)
				(justify left bottom mirror)
			)
		)
		(property "Value" "C_100n_0402"
			(at 0 -1.399999 135)
			(layer "B.Fab")
			(hide yes)
			(effects
				(font
					(size 0.7 0.7)
					(thickness 0.15)
				)
				(justify left bottom mirror)
			)
		)
		(property "Datasheet" "https://www.murata.com/products/productdetail?partno=GRM155R61H104KE14%23"
			(at 0 0 315)
			(layer "F.Fab")
			(hide yes)
			(effects
				(font
					(size 1.27 1.27)
					(thickness 0.15)
				)
			)
		)
		(property "Description" "SMD Multilayer Ceramic Capacitor, 0.1 µF, 50 V, 0402 [1005 Metric], ± 10%, X5R, GRM Series"
			(at 0 0 315)
			(layer "F.Fab")
			(hide yes)
			(effects
				(font
					(size 1.27 1.27)
					(thickness 0.15)
				)
			)
		)
		(property "Author" "Antmicro"
			(at -4.559004 108.233591 0)
			(layer "B.Fab")
			(hide yes)
			(effects
				(font
					(size 1 1)
					(thickness 0.15)
				)
				(justify mirror)
			)
		)
		(property "Dielectric" "X5R"
			(at -4.559004 108.233591 0)
			(layer "B.Fab")
			(hide yes)
			(effects
				(font
					(size 1 1)
					(thickness 0.15)
				)
				(justify mirror)
			)
		)
		(property "License" "Apache-2.0"
			(at -4.559004 108.233591 0)
			(layer "B.Fab")
			(hide yes)
			(effects
				(font
					(size 1 1)
					(thickness 0.15)
				)
				(justify mirror)
			)
		)
		(property "MPN" "GRM155R61H104KE14D"
			(at -4.559004 108.233591 0)
			(layer "B.Fab")
			(hide yes)
			(effects
				(font
					(size 1 1)
					(thickness 0.15)
				)
				(justify mirror)
			)
		)
		(property "Manufacturer" "Murata"
			(at -4.559004 108.233591 0)
			(layer "B.Fab")
			(hide yes)
			(effects
				(font
					(size 1 1)
					(thickness 0.15)
				)
				(justify mirror)
			)
		)
		(property "Val" "100n"
			(at -4.559004 108.233591 0)
			(layer "B.Fab")
			(hide yes)
			(effects
				(font
					(size 1 1)
					(thickness 0.15)
				)
				(justify mirror)
			)
		)
		(property "Voltage" "50V"
			(at -4.559004 108.233591 0)
			(layer "B.Fab")
			(hide yes)
			(effects
				(font
					(size 1 1)
					(thickness 0.15)
				)
				(justify mirror)
			)
		)
		(sheetname "/DDR3/")
		(sheetfile "ddr3.kicad_sch")
		(attr smd)
		(fp_poly
			(pts
				(xy -0.925 0.47) (xy 0.925 0.47) (xy 0.925 -0.47) (xy -0.925 -0.47)
			)
			(stroke
				(width 0.05)
				(type default)
			)
			(fill no)
			(layer "B.CrtYd")
		)
		(fp_line
			(start -0.494 0.25)
			(end 0.504 0.25)
			(stroke
				(width 0.15)
				(type solid)
			)
			(layer "B.Fab")
		)
		(fp_line
			(start -0.494 -0.248)
			(end -0.494 0.25)
			(stroke
				(width 0.15)
				(type solid)
			)
			(layer "B.Fab")
		)
		(fp_line
			(start 0.504 0.25)
			(end 0.504 -0.248)
			(stroke
				(width 0.15)
				(type solid)
			)
			(layer "B.Fab")
		)
		(fp_line
			(start 0.504 -0.248)
			(end -0.494 -0.248)
			(stroke
				(width 0.15)
				(type solid)
			)
			(layer "B.Fab")
		)
		(fp_text user "${REFERENCE}"
			(at -0.939 -4.599 135)
			(layer "B.Fab")
			(effects
				(font
					(size 0.7 0.7)
					(thickness 0.15)
				)
				(justify left bottom mirror)
			)
		)
		(fp_text user "Author: Antmicro"
			(at -0.939 -3.399 135)
			(layer "B.Fab")
			(effects
				(font
					(size 0.7 0.7)
					(thickness 0.15)
				)
				(justify left bottom mirror)
			)
		)
		(fp_text user "License: Apache-2.0"
			(at -0.939 -5.799 135)
			(layer "B.Fab")
			(effects
				(font
					(size 0.7 0.7)
					(thickness 0.15)
				)
				(justify left bottom mirror)
			)
		)
		(pad "1" smd roundrect
			(at -0.48 0 315)
			(size 0.59 0.64)
			(layers "B.Cu" "B.Mask" "B.Paste")
			(roundrect_rratio 0.25)
			(net 1 "GND")
			(pintype "passive")
		)
		(pad "2" smd roundrect
			(at 0.48 0 315)
			(size 0.59 0.64)
			(layers "B.Cu" "B.Mask" "B.Paste")
			(roundrect_rratio 0.25)
			(net 248 "+1V5")
			(pintype "passive")
		)
	)
	(footprint "antmicro-footprints:C_0402_1005Metric"
		(layer "B.Cu")
		(at 162.43 100.95 -90)
		(descr "Capacitor SMD 0402")
		(tags "capacitor SMD 0402")
		(property "Reference" "C2"
			(at -0.61 -1.3 90)
			(layer "B.SilkS")
			(effects
				(font
					(size 0.65 0.65)
					(thickness 0.15)
				)
				(justify left bottom mirror)
			)
		)
		(property "Value" "C_100n_0402"
			(at 0 -1.4 90)
			(layer "B.Fab")
			(hide yes)
			(effects
				(font
					(size 0.7 0.7)
					(thickness 0.15)
				)
				(justify left bottom mirror)
			)
		)
		(property "Datasheet" "https://www.murata.com/products/productdetail?partno=GRM155R61H104KE14%23"
			(at 0 0 270)
			(layer "F.Fab")
			(hide yes)
			(effects
				(font
					(size 1.27 1.27)
					(thickness 0.15)
				)
			)
		)
		(property "Description" "SMD Multilayer Ceramic Capacitor, 0.1 µF, 50 V, 0402 [1005 Metric], ± 10%, X5R, GRM Series"
			(at 0 0 270)
			(layer "F.Fab")
			(hide yes)
			(effects
				(font
					(size 1.27 1.27)
					(thickness 0.15)
				)
			)
		)
		(property "Author" "Antmicro"
			(at 61.48 263.38 0)
			(layer "B.Fab")
			(hide yes)
			(effects
				(font
					(size 1 1)
					(thickness 0.15)
				)
				(justify mirror)
			)
		)
		(property "Dielectric" "X5R"
			(at 61.48 263.38 0)
			(layer "B.Fab")
			(hide yes)
			(effects
				(font
					(size 1 1)
					(thickness 0.15)
				)
				(justify mirror)
			)
		)
		(property "License" "Apache-2.0"
			(at 61.48 263.38 0)
			(layer "B.Fab")
			(hide yes)
			(effects
				(font
					(size 1 1)
					(thickness 0.15)
				)
				(justify mirror)
			)
		)
		(property "MPN" "GRM155R61H104KE14D"
			(at 61.48 263.38 0)
			(layer "B.Fab")
			(hide yes)
			(effects
				(font
					(size 1 1)
					(thickness 0.15)
				)
				(justify mirror)
			)
		)
		(property "Manufacturer" "Murata"
			(at 61.48 263.38 0)
			(layer "B.Fab")
			(hide yes)
			(effects
				(font
					(size 1 1)
					(thickness 0.15)
				)
				(justify mirror)
			)
		)
		(property "Val" "100n"
			(at 61.48 263.38 0)
			(layer "B.Fab")
			(hide yes)
			(effects
				(font
					(size 1 1)
					(thickness 0.15)
				)
				(justify mirror)
			)
		)
		(property "Voltage" "50V"
			(at 61.48 263.38 0)
			(layer "B.Fab")
			(hide yes)
			(effects
				(font
					(size 1 1)
					(thickness 0.15)
				)
				(justify mirror)
			)
		)
		(sheetname "/Power Supply/")
		(sheetfile "supply.kicad_sch")
		(attr smd)
		(fp_rect
			(start -0.925 0.47)
			(end 0.925 -0.47)
			(stroke
				(width 0.05)
				(type default)
			)
			(fill no)
			(layer "B.CrtYd")
		)
		(fp_line
			(start -0.494 0.25)
			(end 0.504 0.25)
			(stroke
				(width 0.15)
				(type solid)
			)
			(layer "B.Fab")
		)
		(fp_line
			(start 0.504 0.25)
			(end 0.504 -0.248)
			(stroke
				(width 0.15)
				(type solid)
			)
			(layer "B.Fab")
		)
		(fp_line
			(start -0.494 -0.248)
			(end -0.494 0.25)
			(stroke
				(width 0.15)
				(type solid)
			)
			(layer "B.Fab")
		)
		(fp_line
			(start 0.504 -0.248)
			(end -0.494 -0.248)
			(stroke
				(width 0.15)
				(type solid)
			)
			(layer "B.Fab")
		)
		(fp_text user "${REFERENCE}"
			(at -0.939 -4.599 90)
			(layer "B.Fab")
			(effects
				(font
					(size 0.7 0.7)
					(thickness 0.15)
				)
				(justify left bottom mirror)
			)
		)
		(fp_text user "Author: Antmicro"
			(at -0.939 -3.399 90)
			(layer "B.Fab")
			(effects
				(font
					(size 0.7 0.7)
					(thickness 0.15)
				)
				(justify left bottom mirror)
			)
		)
		(fp_text user "License: Apache-2.0"
			(at -0.939 -5.799 90)
			(layer "B.Fab")
			(effects
				(font
					(size 0.7 0.7)
					(thickness 0.15)
				)
				(justify left bottom mirror)
			)
		)
		(pad "1" smd roundrect
			(at -0.48 0 270)
			(size 0.59 0.64)
			(layers "B.Cu" "B.Mask" "B.Paste")
			(roundrect_rratio 0.25)
			(net 1 "GND")
			(pintype "passive")
		)
		(pad "2" smd roundrect
			(at 0.48 0 270)
			(size 0.59 0.64)
			(layers "B.Cu" "B.Mask" "B.Paste")
			(roundrect_rratio 0.25)
			(net 14 "+5V")
			(pintype "passive")
		)
	)
	(footprint "antmicro-footprints:R_0402_1005Metric"
		(layer "B.Cu")
		(at 162.43 104.865 90)
		(descr "Resistor SMD 0402")
		(tags "resistor SMD 0402")
		(property "Reference" "R3"
			(at 0.725 1.3 270)
			(layer "B.SilkS")
			(effects
				(font
					(size 0.65 0.65)
					(thickness 0.15)
				)
				(justify left bottom mirror)
			)
		)
		(property "Value" "R_1k_0402"
			(at 0 -1.4 270)
			(layer "B.Fab")
			(hide yes)
			(effects
				(font
					(size 0.7 0.7)
					(thickness 0.15)
				)
				(justify left bottom mirror)
			)
		)
		(property "Datasheet" "https://www.bourns.com/docs/product-datasheets/cr.pdf"
			(at 0 0 90)
			(layer "F.Fab")
			(hide yes)
			(effects
				(font
					(size 1.27 1.27)
					(thickness 0.15)
				)
			)
		)
		(property "Description" "SMD Chip Resistor, 1 kohm, ± 1%, 63 mW, 0402 [1005 Metric], Thick Film, General Purpose"
			(at 0 0 90)
			(layer "F.Fab")
			(hide yes)
			(effects
				(font
					(size 1.27 1.27)
					(thickness 0.15)
				)
			)
		)
		(property "Author" "Antmicro"
			(at 267.295 -57.565 0)
			(layer "B.Fab")
			(hide yes)
			(effects
				(font
					(size 1 1)
					(thickness 0.15)
				)
				(justify mirror)
			)
		)
		(property "License" "Apache-2.0"
			(at 267.295 -57.565 0)
			(layer "B.Fab")
			(hide yes)
			(effects
				(font
					(size 1 1)
					(thickness 0.15)
				)
				(justify mirror)
			)
		)
		(property "MPN" "CR0402-FX-1001GLF"
			(at 267.295 -57.565 0)
			(layer "B.Fab")
			(hide yes)
			(effects
				(font
					(size 1 1)
					(thickness 0.15)
				)
				(justify mirror)
			)
		)
		(property "Manufacturer" "Bourns"
			(at 267.295 -57.565 0)
			(layer "B.Fab")
			(hide yes)
			(effects
				(font
					(size 1 1)
					(thickness 0.15)
				)
				(justify mirror)
			)
		)
		(property "Tolerance" "1%"
			(at 267.295 -57.565 0)
			(layer "B.Fab")
			(hide yes)
			(effects
				(font
					(size 1 1)
					(thickness 0.15)
				)
				(justify mirror)
			)
		)
		(property "Val" "1k"
			(at 267.295 -57.565 0)
			(layer "B.Fab")
			(hide yes)
			(effects
				(font
					(size 1 1)
					(thickness 0.15)
				)
				(justify mirror)
			)
		)
		(sheetname "/Power Supply/")
		(sheetfile "supply.kicad_sch")
		(attr smd)
		(fp_rect
			(start -0.925 0.47)
			(end 0.925 -0.47)
			(stroke
				(width 0.05)
				(type default)
			)
			(fill no)
			(layer "B.CrtYd")
		)
		(fp_rect
			(start -0.5 0.25)
			(end 0.5 -0.25)
			(stroke
				(width 0.15)
				(type solid)
			)
			(fill no)
			(layer "B.Fab")
		)
		(fp_text user "License: Apache-2.0"
			(at -0.95 -5.169 270)
			(layer "B.Fab")
			(effects
				(font
					(size 0.7 0.7)
					(thickness 0.15)
				)
				(justify left bottom mirror)
			)
		)
		(fp_text user "${REFERENCE}"
			(at -0.95 -3.168 270)
			(layer "B.Fab")
			(effects
				(font
					(size 0.7 0.7)
					(thickness 0.15)
				)
				(justify left bottom mirror)
			)
		)
		(fp_text user "Author: Antmicro"
			(at -0.95 -4.169 270)
			(layer "B.Fab")
			(effects
				(font
					(size 0.7 0.7)
					(thickness 0.15)
				)
				(justify left bottom mirror)
			)
		)
		(pad "1" smd roundrect
			(at -0.48 0 90)
			(size 0.59 0.64)
			(layers "B.Cu" "B.Mask" "B.Paste")
			(roundrect_rratio 0.25)
			(net 1 "GND")
			(pintype "passive")
		)
		(pad "2" smd roundrect
			(at 0.48 0 90)
			(size 0.59 0.64)
			(layers "B.Cu" "B.Mask" "B.Paste")
			(roundrect_rratio 0.25)
			(net 141 "/Power Supply/VREF_0V45")
			(pintype "passive")
		)
	)
	(footprint "antmicro-footprints:C_0201"
		(layer "B.Cu")
		(at 124.35 86.75 45)
		(descr "Capacitor SMD 0201")
		(tags "capacitor SMD 0201")
		(property "Reference" "C35"
			(at 1.149569 -15.178567 45)
			(layer "B.SilkS")
			(effects
				(font
					(size 0.65 0.65)
					(thickness 0.15)
				)
				(justify right bottom mirror)
			)
		)
		(property "Value" "C_100n_0201"
			(at 0 -1.399999 45)
			(layer "B.Fab")
			(hide yes)
			(effects
				(font
					(size 0.7 0.7)
					(thickness 0.15)
				)
				(justify right bottom mirror)
			)
		)
		(property "Datasheet" "https://www.yageo.com/en/Chart/Download/pdf/CC0201KRX6S5BB104"
			(at 0 0 45)
			(layer "F.Fab")
			(hide yes)
			(effects
				(font
					(size 1.27 1.27)
					(thickness 0.15)
				)
			)
		)
		(property "Description" "SMD Multilayer Ceramic Capacitor, 0.1 µF, 6.3 V, 0201 [0603 Metric], ± 10%, X6S, CC Series"
			(at 0 0 45)
			(layer "F.Fab")
			(hide yes)
			(effects
				(font
					(size 1.27 1.27)
					(thickness 0.15)
				)
			)
		)
		(property "Author" "Antmicro"
			(at 97.762785 -62.520241 0)
			(layer "B.Fab")
			(hide yes)
			(effects
				(font
					(size 1 1)
					(thickness 0.15)
				)
				(justify mirror)
			)
		)
		(property "Dielectric" ""
			(at 97.762785 -62.520241 0)
			(layer "B.Fab")
			(hide yes)
			(effects
				(font
					(size 1 1)
					(thickness 0.15)
				)
				(justify mirror)
			)
		)
		(property "License" "Apache-2.0"
			(at 97.762785 -62.520241 0)
			(layer "B.Fab")
			(hide yes)
			(effects
				(font
					(size 1 1)
					(thickness 0.15)
				)
				(justify mirror)
			)
		)
		(property "MPN" "CC0201KRX6S5BB104"
			(at 97.762785 -62.520241 0)
			(layer "B.Fab")
			(hide yes)
			(effects
				(font
					(size 1 1)
					(thickness 0.15)
				)
				(justify mirror)
			)
		)
		(property "Manufacturer" "YAGEO"
			(at 97.762785 -62.520241 0)
			(layer "B.Fab")
			(hide yes)
			(effects
				(font
					(size 1 1)
					(thickness 0.15)
				)
				(justify mirror)
			)
		)
		(property "Val" "100n"
			(at 97.762785 -62.520241 0)
			(layer "B.Fab")
			(hide yes)
			(effects
				(font
					(size 1 1)
					(thickness 0.15)
				)
				(justify mirror)
			)
		)
		(property "Voltage" ""
			(at 97.762785 -62.520241 0)
			(layer "B.Fab")
			(hide yes)
			(effects
				(font
					(size 1 1)
					(thickness 0.15)
				)
				(justify mirror)
			)
		)
		(property "Public" "False"
			(at 0 0 45)
			(unlocked yes)
			(layer "B.Fab")
			(hide yes)
			(effects
				(font
					(size 1 1)
					(thickness 0.15)
				)
				(justify mirror)
			)
		)
		(sheetname "/DDR3/")
		(sheetfile "ddr3.kicad_sch")
		(attr smd)
		(fp_poly
			(pts
				(xy -0.7 0.35) (xy 0.7 0.35) (xy 0.7 -0.35) (xy -0.7 -0.35)
			)
			(stroke
				(width 0.05)
				(type default)
			)
			(fill no)
			(layer "B.CrtYd")
		)
		(fp_poly
			(pts
				(xy 0.3 -0.15) (xy -0.301 -0.15) (xy -0.301 0.149) (xy 0.3 0.149)
			)
			(stroke
				(width 0.15)
				(type solid)
			)
			(fill no)
			(layer "B.Fab")
		)
		(fp_text user "Author: Antmicro"
			(at -0.72 -5.400001 225)
			(layer "B.Fab")
			(effects
				(font
					(size 0.7 0.7)
					(thickness 0.15)
				)
				(justify left bottom mirror)
			)
		)
		(fp_text user "${REFERENCE}"
			(at -0.72 -3.4 225)
			(layer "B.Fab")
			(effects
				(font
					(size 0.7 0.7)
					(thickness 0.15)
				)
				(justify left bottom mirror)
			)
		)
		(fp_text user "License: Apache-2.0"
			(at -0.72 -4.4 225)
			(layer "B.Fab")
			(effects
				(font
					(size 0.7 0.7)
					(thickness 0.15)
				)
				(justify left bottom mirror)
			)
		)
		(pad "" smd roundrect
			(at -0.349 0.002 45)
			(size 0.318 0.36)
			(layers "B.Paste")
			(roundrect_rratio 0.25)
		)
		(pad "" smd roundrect
			(at 0.341 0.002 45)
			(size 0.318 0.36)
			(layers "B.Paste")
			(roundrect_rratio 0.25)
		)
		(pad "1" smd roundrect
			(at -0.321 0.002 45)
			(size 0.46 0.4)
			(layers "B.Cu" "B.Mask")
			(roundrect_rratio 0.25)
			(net 1 "GND")
			(pintype "passive")
		)
		(pad "2" smd roundrect
			(at 0.32 0.002 45)
			(size 0.46 0.4)
			(layers "B.Cu" "B.Mask")
			(roundrect_rratio 0.25)
			(net 248 "+1V5")
			(pintype "passive")
		)
	)
)
